(kicad_pcb
	(version 20221018)
	(generator pcbnew)
	(general
    (thickness 1.7403)
  )
	(paper "A4")
	(title_block
    (title "Data Center RDIMM DDR4 Tester")
    (date "2024-09-30")
    (rev "1.2.4")
		(comment 9 "footprints 616-622 of 690")
	)
	(layers
    (0 "F.Cu" signal)
    (1 "In1.Cu" power)
    (2 "In2.Cu" signal)
    (3 "In3.Cu" power)
    (4 "In4.Cu" power)
    (5 "In5.Cu" signal)
    (6 "In6.Cu" power)
    (7 "In7.Cu" signal)
    (8 "In8.Cu" power)
    (9 "In9.Cu" signal)
    (10 "In10.Cu" power)
    (31 "B.Cu" signal)
    (32 "B.Adhes" user "B.Adhesive")
    (33 "F.Adhes" user "F.Adhesive")
    (34 "B.Paste" user)
    (35 "F.Paste" user)
    (36 "B.SilkS" user "B.Silkscreen")
    (37 "F.SilkS" user "F.Silkscreen")
    (38 "B.Mask" user)
    (39 "F.Mask" user)
    (40 "Dwgs.User" user "User.Drawings")
    (41 "Cmts.User" user "User.Comments")
    (42 "Eco1.User" user "User.Eco1")
    (43 "Eco2.User" user "User.Eco2")
    (44 "Edge.Cuts" user)
    (45 "Margin" user)
    (46 "B.CrtYd" user "B.Courtyard")
    (47 "F.CrtYd" user "F.Courtyard")
    (48 "B.Fab" user)
    (49 "F.Fab" user)
  )
	(footprint "data-center-rdimm-ddr4-tester-footprints:C_0201" (layer "B.Cu")
    (at 194.2 101.6 180)
    (descr "Capacitor SMD 0201")
    (tags "capacitor SMD 0201")
    (property "Author" "Antmicro")
    (property "Dielectric" "")
    (property "License" "Apache-2.0")
    (property "MPN" "CC0201KRX6S5BB104")
    (property "Manufacturer" "Yaego")
    (property "Sheetfile" "fpga-power.kicad_sch")
    (property "Sheetname" "FPGA power")
    (property "Val" "100n")
    (property "Voltage" "")
    (property "ki_description" " ")
    (attr smd)
    (fp_text reference "C248" (at -3.44 -0.37) (layer "B.SilkS")
        (effects (font (size 0.7 0.7) (thickness 0.15)) (justify left bottom mirror))
    )
    (fp_text value "C_100n_0201" (at 0 -1.4) (layer "B.Fab") hide
        (effects (font (size 0.7 0.7) (thickness 0.15)) (justify left bottom mirror))
    )
    (fp_text user "${REFERENCE}" (at -0.72 -3.4) (layer "B.Fab") hide
        (effects (font (size 0.7 0.7) (thickness 0.15)) (justify left bottom mirror))
    )
    (fp_text user "License: Apache-2.0" (at -0.72 -4.4) (layer "B.Fab") hide
        (effects (font (size 0.7 0.7) (thickness 0.15)) (justify left bottom mirror))
    )
    (fp_text user "Author: Antmicro" (at -0.72 -5.4) (layer "B.Fab") hide
        (effects (font (size 0.7 0.7) (thickness 0.15)) (justify left bottom mirror))
    )
    (fp_rect (start -0.72 0.38) (end 0.72 -0.38)
      (stroke (width 0.05) (type solid)) (fill none) (layer "B.CrtYd"))
    (fp_rect (start 0.3 -0.15) (end -0.301 0.149)
      (stroke (width 0.15) (type solid)) (fill none) (layer "B.Fab"))
    (pad "" smd roundrect (at -0.349 0.002 180) (size 0.318 0.36) (layers "B.Paste") (roundrect_rratio 0.25))
    (pad "" smd roundrect (at 0.341 0.002 180) (size 0.318 0.36) (layers "B.Paste") (roundrect_rratio 0.25))
    (pad "1" smd roundrect (at -0.321 0.002 180) (size 0.46 0.4) (layers "B.Cu" "B.Mask") (roundrect_rratio 0.25)
      (net 306 "1V2_SYS") (pintype "passive"))
    (pad "2" smd roundrect (at 0.32 0.002 180) (size 0.46 0.4) (layers "B.Cu" "B.Mask") (roundrect_rratio 0.25)
      (net 9 "GND") (pintype "passive"))
  )
	(footprint "data-center-rdimm-ddr4-tester-footprints:C_0805_2012Metric" (layer "B.Cu")
    (at 188.1 124.5 180)
    (descr "Capacitor SMD 0805")
    (tags "capacitor SMD 0805")
    (property "Author" "Antmicro")
    (property "Dielectric" "X7R")
    (property "License" "Apache-2.0")
    (property "MPN" "CL21B104KCFNNNE")
    (property "Manufacturer" "SAMSUNG")
    (property "Sheetfile" "ethernet.kicad_sch")
    (property "Sheetname" "Ethernet")
    (property "Val" "100n/100V")
    (property "Voltage" "100V")
    (property "ki_description" " ")
    (attr smd)
    (fp_text reference "C222" (at -1.39 1.03) (layer "B.SilkS")
        (effects (font (size 0.7 0.7) (thickness 0.15)) (justify left bottom mirror))
    )
    (fp_text value "C_100n_0805_100V" (at 0 -1.947) (layer "B.Fab") hide
        (effects (font (size 0.7 0.7) (thickness 0.15)) (justify left bottom mirror))
    )
    (fp_text user "Author: Antmicro" (at -1.9 -5.947) (layer "B.Fab") hide
        (effects (font (size 0.7 0.7) (thickness 0.15)) (justify left bottom mirror))
    )
    (fp_text user "${REFERENCE}" (at -1.9 -3.947) (layer "B.Fab") hide
        (effects (font (size 0.7 0.7) (thickness 0.15)) (justify left bottom mirror))
    )
    (fp_text user "License: Apache-2.0" (at -1.9 -4.947) (layer "B.Fab") hide
        (effects (font (size 0.7 0.7) (thickness 0.15)) (justify left bottom mirror))
    )
    (fp_line (start -0.3 -0.8) (end 0.3 -0.8)
      (stroke (width 0.15) (type solid)) (layer "B.SilkS"))
    (fp_line (start -0.3 0.8) (end 0.3 0.8)
      (stroke (width 0.15) (type solid)) (layer "B.SilkS"))
    (fp_rect (start -1.9 0.93) (end 1.9 -0.93)
      (stroke (width 0.05) (type solid)) (fill none) (layer "B.CrtYd"))
    (fp_rect (start -0.95 0.675) (end 0.95 -0.675)
      (stroke (width 0.15) (type solid)) (fill none) (layer "B.Fab"))
    (pad "1" smd rect (at -1.05 0 180) (size 1.2 1.2) (layers "B.Cu" "B.Paste" "B.Mask")
      (net 360 "/Ethernet/VDD") (pintype "passive"))
    (pad "2" smd rect (at 1.05 0 180) (size 1.2 1.2) (layers "B.Cu" "B.Paste" "B.Mask")
      (net 381 "/Ethernet/VSS") (pintype "passive"))
  )
	(footprint "data-center-rdimm-ddr4-tester-footprints:SOT-753" (layer "B.Cu")
    (at 136.29 99.74 -90)
    (property "Author" "Antmicro")
    (property "License" "Apache-2.0")
    (property "MPN" "SN74AHCT1G125DBVR")
    (property "Manufacturer" "Texas Instruments")
    (property "Sheetfile" "supply.kicad_sch")
    (property "Sheetname" "Supply")
    (attr smd)
    (fp_text reference "U22" (at -1.16 2.04 90) (layer "B.SilkS")
        (effects (font (size 0.7 0.7) (thickness 0.15)) (justify left bottom mirror))
    )
    (fp_text value "SN74AHCT1G125_SOT" (at 0 -2.9 90) (layer "B.Fab") hide
        (effects (font (size 0.7 0.7) (thickness 0.15)) (justify left bottom mirror))
    )
    (fp_text user "Author: Antmicro" (at -1.651 -7.225 90) (layer "B.Fab") hide
        (effects (font (size 0.7 0.7) (thickness 0.15)) (justify left bottom mirror))
    )
    (fp_text user "${REFERENCE}" (at -1.651 -6.025 90) (layer "B.Fab") hide
        (effects (font (size 0.7 0.7) (thickness 0.15)) (justify left bottom mirror))
    )
    (fp_text user "License: Apache-2.0" (at -1.651 -8.425 90) (layer "B.Fab") hide
        (effects (font (size 0.7 0.7) (thickness 0.15)) (justify left bottom mirror))
    )
    (fp_line (start -1.651 1) (end -1.651 0.701)
      (stroke (width 0.15) (type solid)) (layer "B.SilkS"))
    (fp_line (start -1.648 -1) (end -1.648 -0.677)
      (stroke (width 0.15) (type solid)) (layer "B.SilkS"))
    (fp_line (start -1.5 -1) (end -1.648 -1)
      (stroke (width 0.15) (type solid)) (layer "B.SilkS"))
    (fp_line (start -1.5 1) (end -1.651 1)
      (stroke (width 0.15) (type solid)) (layer "B.SilkS"))
    (fp_line (start 1.5 -0.998) (end 1.648 -0.998)
      (stroke (width 0.15) (type solid)) (layer "B.SilkS"))
    (fp_line (start 1.5 1) (end 1.648 1)
      (stroke (width 0.15) (type solid)) (layer "B.SilkS"))
    (fp_line (start 1.648 -0.998) (end 1.648 -0.699)
      (stroke (width 0.15) (type solid)) (layer "B.SilkS"))
    (fp_line (start 1.648 1) (end 1.648 0.677)
      (stroke (width 0.15) (type solid)) (layer "B.SilkS"))
    (fp_circle (center -1.5 -1.35) (end -1.46 -1.4)
      (stroke (width 0.15) (type solid)) (fill solid) (layer "B.SilkS"))
    (fp_rect (start -1.7 1.901) (end 1.699 -1.898)
      (stroke (width 0.05) (type solid)) (fill none) (layer "B.CrtYd"))
    (fp_line (start -1.526 -0.623) (end -1.526 0.875)
      (stroke (width 0.15) (type solid)) (layer "B.Fab"))
    (fp_line (start -1.526 -0.623) (end -1.351 -0.873)
      (stroke (width 0.15) (type solid)) (layer "B.Fab"))
    (fp_line (start -1.526 0.875) (end 1.523 0.875)
      (stroke (width 0.15) (type solid)) (layer "B.Fab"))
    (fp_line (start -1.351 -0.873) (end 1.523 -0.873)
      (stroke (width 0.15) (type solid)) (layer "B.Fab"))
    (fp_line (start 1.523 0.875) (end 1.523 -0.873)
      (stroke (width 0.15) (type solid)) (layer "B.Fab"))
    (pad "1" smd roundrect (at -0.951 -1.35 270) (size 0.6 1.05) (layers "B.Cu" "B.Paste" "B.Mask") (roundrect_rratio 0.25)
      (net 800 "FPGA_VTT_CNTL") (pinfunction "~{OE}") (pintype "input"))
    (pad "2" smd roundrect (at 0 -1.35 270) (size 0.6 1.05) (layers "B.Cu" "B.Paste" "B.Mask") (roundrect_rratio 0.25)
      (net 153 "/Supply/VCC_IO_EN") (pinfunction "A") (pintype "input"))
    (pad "3" smd roundrect (at 0.949 -1.35 270) (size 0.6 1.05) (layers "B.Cu" "B.Paste" "B.Mask") (roundrect_rratio 0.25)
      (net 9 "GND") (pinfunction "GND") (pintype "power_in"))
    (pad "4" smd roundrect (at 0.949 1.351 270) (size 0.6 1.05) (layers "B.Cu" "B.Paste" "B.Mask") (roundrect_rratio 0.25)
      (net 793 "/Supply/VTT_CNTL") (pinfunction "Y") (pintype "output"))
    (pad "5" smd roundrect (at -0.951 1.351 270) (size 0.6 1.05) (layers "B.Cu" "B.Paste" "B.Mask") (roundrect_rratio 0.25)
      (net 307 "5V0_SYS") (pinfunction "V_{CC}") (pintype "power_in"))
  )
	(footprint "data-center-rdimm-ddr4-tester-footprints:R_0402_1005Metric" (layer "B.Cu")
    (at 122.525 96.45 -90)
    (descr "Resistor SMD 0402")
    (tags "resistor SMD 0402")
    (property "Author" "Antmicro")
    (property "Current" "1A")
    (property "DNP" "DNP")
    (property "License" "Apache-2.0")
    (property "MPN" "ERJ2GE0R00X")
    (property "Manufacturer" "Panasonic")
    (property "Sheetfile" "supply.kicad_sch")
    (property "Sheetname" "Supply")
    (property "Tolerance" "")
    (property "Val" "0R")
    (property "dnp" "")
    (property "exclude_from_bom" "")
    (property "ki_description" "0R resistor in 0402 package with unspecified tolerance")
    (attr exclude_from_pos_files exclude_from_bom)
    (fp_text reference "R197" (at -1.87 -1.355 90) (layer "B.SilkS")
        (effects (font (size 0.7 0.7) (thickness 0.15)) (justify left bottom mirror))
    )
    (fp_text value "R_0R_0402" (at 0 -1.4 90) (layer "B.Fab") hide
        (effects (font (size 0.7 0.7) (thickness 0.15)) (justify left bottom mirror))
    )
    (fp_text user "Author: Antmicro" (at -0.95 -4.169 90) (layer "B.Fab") hide
        (effects (font (size 0.7 0.7) (thickness 0.15)) (justify left bottom mirror))
    )
    (fp_text user "License: Apache-2.0" (at -0.95 -5.169 90) (layer "B.Fab") hide
        (effects (font (size 0.7 0.7) (thickness 0.15)) (justify left bottom mirror))
    )
    (fp_text user "${REFERENCE}" (at -0.95 -3.168 90) (layer "B.Fab") hide
        (effects (font (size 0.7 0.7) (thickness 0.15)) (justify left bottom mirror))
    )
    (fp_rect (start -0.93 0.47) (end 0.93 -0.47)
      (stroke (width 0.05) (type solid)) (fill none) (layer "B.CrtYd"))
    (fp_rect (start -0.5 0.25) (end 0.5 -0.25)
      (stroke (width 0.15) (type solid)) (fill none) (layer "B.Fab"))
    (pad "1" smd roundrect (at -0.485 0 270) (size 0.59 0.64) (layers "B.Cu" "B.Paste" "B.Mask") (roundrect_rratio 0.25)
      (net 152 "/Supply/VCC_AUX_EN") (pintype "passive"))
    (pad "2" smd roundrect (at 0.485 0 270) (size 0.59 0.64) (layers "B.Cu" "B.Paste" "B.Mask") (roundrect_rratio 0.25)
      (net 794 "/Supply/SLP_S4") (pintype "passive"))
  )
	(footprint "data-center-rdimm-ddr4-tester-footprints:C_0402_1005Metric" (layer "B.Cu")
    (at 130.075 111.2 180)
    (descr "Capacitor SMD 0402")
    (tags "capacitor SMD 0402")
    (property "Author" "Antmicro")
    (property "Dielectric" "X5R")
    (property "License" "Apache-2.0")
    (property "MPN" "GRM155R61H104KE14D")
    (property "Manufacturer" "Murata")
    (property "Sheetfile" "supply.kicad_sch")
    (property "Sheetname" "Supply")
    (property "Val" "100n")
    (property "Voltage" "50V")
    (property "ki_description" " ")
    (attr smd)
    (fp_text reference "C233" (at -0.825 -1.3) (layer "B.SilkS")
        (effects (font (size 0.7 0.7) (thickness 0.15)) (justify left bottom mirror))
    )
    (fp_text value "C_100n_0402" (at 0 -1.4) (layer "B.Fab") hide
        (effects (font (size 0.7 0.7) (thickness 0.15)) (justify left bottom mirror))
    )
    (fp_text user "License: Apache-2.0" (at -0.932 -5.17) (layer "B.Fab") hide
        (effects (font (size 0.7 0.7) (thickness 0.15)) (justify left bottom mirror))
    )
    (fp_text user "Author: Antmicro" (at -0.932 -4.17) (layer "B.Fab") hide
        (effects (font (size 0.7 0.7) (thickness 0.15)) (justify left bottom mirror))
    )
    (fp_text user "${REFERENCE}" (at -0.932 -3.168) (layer "B.Fab") hide
        (effects (font (size 0.7 0.7) (thickness 0.15)) (justify left bottom mirror))
    )
    (fp_rect (start -0.94 0.47) (end 0.94 -0.47)
      (stroke (width 0.05) (type solid)) (fill none) (layer "B.CrtYd"))
    (fp_rect (start -0.499 0.249) (end 0.499 -0.249)
      (stroke (width 0.15) (type solid)) (fill none) (layer "B.Fab"))
    (pad "1" smd roundrect (at -0.484 0 180) (size 0.59 0.64) (layers "B.Cu" "B.Paste" "B.Mask") (roundrect_rratio 0.25)
      (net 307 "5V0_SYS") (pintype "passive"))
    (pad "2" smd roundrect (at 0.484 0 180) (size 0.59 0.64) (layers "B.Cu" "B.Paste" "B.Mask") (roundrect_rratio 0.25)
      (net 9 "GND") (pintype "passive"))
  )
	(footprint "data-center-rdimm-ddr4-tester-footprints:C_0201" (layer "B.Cu")
    (at 184.175 98.725 180)
    (descr "Capacitor SMD 0201")
    (tags "capacitor SMD 0201")
    (property "Author" "Antmicro")
    (property "Dielectric" "")
    (property "License" "Apache-2.0")
    (property "MPN" "CC0201KRX6S5BB104")
    (property "Manufacturer" "Yaego")
    (property "Sheetfile" "fpga-power.kicad_sch")
    (property "Sheetname" "FPGA power")
    (property "Val" "100n")
    (property "Voltage" "")
    (property "ki_description" " ")
    (attr smd)
    (fp_text reference "C310" (at -1.955 0.515) (layer "B.SilkS")
        (effects (font (size 0.7 0.7) (thickness 0.15)) (justify left bottom mirror))
    )
    (fp_text value "C_100n_0201" (at 0 -1.4) (layer "B.Fab") hide
        (effects (font (size 0.7 0.7) (thickness 0.15)) (justify left bottom mirror))
    )
    (fp_text user "Author: Antmicro" (at -0.72 -5.4) (layer "B.Fab") hide
        (effects (font (size 0.7 0.7) (thickness 0.15)) (justify left bottom mirror))
    )
    (fp_text user "${REFERENCE}" (at -0.72 -3.4) (layer "B.Fab") hide
        (effects (font (size 0.7 0.7) (thickness 0.15)) (justify left bottom mirror))
    )
    (fp_text user "License: Apache-2.0" (at -0.72 -4.4) (layer "B.Fab") hide
        (effects (font (size 0.7 0.7) (thickness 0.15)) (justify left bottom mirror))
    )
    (fp_rect (start -0.72 0.38) (end 0.72 -0.38)
      (stroke (width 0.05) (type solid)) (fill none) (layer "B.CrtYd"))
    (fp_rect (start 0.3 -0.15) (end -0.301 0.149)
      (stroke (width 0.15) (type solid)) (fill none) (layer "B.Fab"))
    (pad "" smd roundrect (at -0.349 0.002 180) (size 0.318 0.36) (layers "B.Paste") (roundrect_rratio 0.25))
    (pad "" smd roundrect (at 0.341 0.002 180) (size 0.318 0.36) (layers "B.Paste") (roundrect_rratio 0.25))
    (pad "1" smd roundrect (at -0.321 0.002 180) (size 0.46 0.4) (layers "B.Cu" "B.Mask") (roundrect_rratio 0.25)
      (net 143 "3V3_SYS") (pintype "passive"))
    (pad "2" smd roundrect (at 0.32 0.002 180) (size 0.46 0.4) (layers "B.Cu" "B.Mask") (roundrect_rratio 0.25)
      (net 9 "GND") (pintype "passive"))
  )
	(footprint "data-center-rdimm-ddr4-tester-footprints:C_0201" (layer "B.Cu")
    (at 173.1 98.05 -90)
    (descr "Capacitor SMD 0201")
    (tags "capacitor SMD 0201")
    (property "Author" "Antmicro")
    (property "Dielectric" "")
    (property "License" "Apache-2.0")
    (property "MPN" "CC0201KRX6S5BB104")
    (property "Manufacturer" "Yaego")
    (property "Sheetfile" "fpga-power.kicad_sch")
    (property "Sheetname" "FPGA power")
    (property "Val" "100n")
    (property "Voltage" "")
    (property "ki_description" " ")
    (attr smd)
    (fp_text reference "C299" (at -1.41 0.52 90) (layer "B.SilkS")
        (effects (font (size 0.7 0.7) (thickness 0.15)) (justify left bottom mirror))
    )
    (fp_text value "C_100n_0201" (at 0 -1.4 90) (layer "B.Fab") hide
        (effects (font (size 0.7 0.7) (thickness 0.15)) (justify left bottom mirror))
    )
    (fp_text user "${REFERENCE}" (at -0.72 -3.4 90) (layer "B.Fab") hide
        (effects (font (size 0.7 0.7) (thickness 0.15)) (justify left bottom mirror))
    )
    (fp_text user "License: Apache-2.0" (at -0.72 -4.4 90) (layer "B.Fab") hide
        (effects (font (size 0.7 0.7) (thickness 0.15)) (justify left bottom mirror))
    )
    (fp_text user "Author: Antmicro" (at -0.72 -5.4 90) (layer "B.Fab") hide
        (effects (font (size 0.7 0.7) (thickness 0.15)) (justify left bottom mirror))
    )
    (fp_rect (start -0.72 0.38) (end 0.72 -0.38)
      (stroke (width 0.05) (type solid)) (fill none) (layer "B.CrtYd"))
    (fp_rect (start 0.3 -0.15) (end -0.301 0.149)
      (stroke (width 0.15) (type solid)) (fill none) (layer "B.Fab"))
    (pad "" smd roundrect (at -0.349 0.002 270) (size 0.318 0.36) (layers "B.Paste") (roundrect_rratio 0.25))
    (pad "" smd roundrect (at 0.341 0.002 270) (size 0.318 0.36) (layers "B.Paste") (roundrect_rratio 0.25))
    (pad "1" smd roundrect (at -0.321 0.002 270) (size 0.46 0.4) (layers "B.Cu" "B.Mask") (roundrect_rratio 0.25)
      (net 143 "3V3_SYS") (pintype "passive"))
    (pad "2" smd roundrect (at 0.32 0.002 270) (size 0.46 0.4) (layers "B.Cu" "B.Mask") (roundrect_rratio 0.25)
      (net 9 "GND") (pintype "passive"))
  )
)
